# S9S_MB_2U (Grand Teton) — schematic netlist excerpt (pin names and nets, part order shuffled) for the footprints in the layout excerpt that follows; sources: Cadence DE-HDL packaged netlist, KiCad conversion of 03242023_DA0F0TMBIJ0_F0T_Motherboard_J_brd_V01_OCP.brd

R4648  Q_RES  1K 1% EMPTY  pkg 0402LF  page 167 : A = P3V3_AUX ; B = FM_P2E_BUF2_EQA1
PR3916  Q_RES  0 5% CHIP  pkg 0402LF  page 302 : A = HSC_SCREF ; B = HSC_SCREF_1

(kicad_pcb
	(version 20260206)
	(generator "pcbnew")
	(generator_version "10.0")
	(general
		(thickness 1.6)
		(legacy_teardrops no)
	)
	(paper "A4")
	(title_block
		(title "03242023_DA0F0TMBIJ0_F0T_Motherboard_J_brd_V01_OCP.brd")
		(comment 1 "Grand Teton / footprints 3075-3076 of 6105")
	)
	(layers
		(0 "F.Cu" signal "TOP")
		(4 "In1.Cu" signal "GND")
		(6 "In2.Cu" signal "IN1")
		(8 "In3.Cu" signal "GND1")
		(10 "In4.Cu" signal "IN2")
		(12 "In5.Cu" signal "GND2")
		(14 "In6.Cu" signal "IN3")
		(16 "In7.Cu" signal "GND3")
		(18 "In8.Cu" signal "VCC")
		(20 "In9.Cu" signal "VCC1")
		(22 "In10.Cu" signal "GND4")
		(24 "In11.Cu" signal "IN4")
		(26 "In12.Cu" signal "GND5")
		(28 "In13.Cu" signal "IN5")
		(30 "In14.Cu" signal "GND6")
		(32 "In15.Cu" signal "IN6")
		(34 "In16.Cu" signal "GND7")
		(2 "B.Cu" signal "BOTTOM")
		(9 "F.Adhes" user "F.Adhesive")
		(11 "B.Adhes" user "B.Adhesive")
		(13 "F.Paste" user "Package Geometry/Pastemask Top")
		(15 "B.Paste" user "Package Geometry/Pastemask Bottom")
		(5 "F.SilkS" user "Ref Des/Silkscreen Top")
		(7 "B.SilkS" user "Ref Des/Silkscreen Bottom")
		(1 "F.Mask" user "Board Geometry/Soldermask Top")
		(3 "B.Mask" user "Board Geometry/Soldermask Bottom")
		(17 "Dwgs.User" user "User.Drawings")
		(19 "Cmts.User" user "User.Comments")
		(21 "Eco1.User" user "User.Eco1")
		(23 "Eco2.User" user "User.Eco2")
		(25 "Edge.Cuts" user "Board Geometry/Outline")
		(27 "Margin" user)
		(31 "F.CrtYd" user "Package Geometry/Place Bound Top")
		(29 "B.CrtYd" user "Package Geometry/Place Bound Bottom")
		(35 "F.Fab" user "Ref Des/Assembly Top")
		(33 "B.Fab" user "Ref Des/Assembly Bottom")
	)
	(footprint ""
		(layer "F.Cu")
		(at 40.389556 -400.153886 -90)
		(property "Reference" "R4648"
			(at 0 0 270)
			(layer "F.SilkS")
			(hide yes)
			(effects
				(font
					(size 1.27 1.27)
				)
			)
		)
		(property "Value" ""
			(at 0 0 270)
			(layer "F.Fab")
			(effects
				(font
					(size 1.27 1.27)
				)
			)
		)
		(duplicate_pad_numbers_are_jumpers no)
		(fp_line
			(start -0.7874 0.4064)
			(end -0.7874 -0.4064)
			(stroke
				(width 0.1524)
				(type default)
			)
			(layer "F.SilkS")
		)
		(fp_line
			(start 0.7874 0.4064)
			(end -0.7874 0.4064)
			(stroke
				(width 0.1524)
				(type default)
			)
			(layer "F.SilkS")
		)
		(fp_line
			(start -0.7874 -0.4064)
			(end 0.7874 -0.4064)
			(stroke
				(width 0.1524)
				(type default)
			)
			(layer "F.SilkS")
		)
		(fp_line
			(start 0.7874 -0.4064)
			(end 0.7874 0.4064)
			(stroke
				(width 0.1524)
				(type default)
			)
			(layer "F.SilkS")
		)
		(fp_line
			(start -0.67945 0.3048)
			(end -0.67945 -0.305054)
			(stroke
				(width 0.1)
				(type default)
			)
			(layer "F.Fab")
		)
		(fp_line
			(start -0.12065 0.3048)
			(end -0.67945 0.3048)
			(stroke
				(width 0.1)
				(type default)
			)
			(layer "F.Fab")
		)
		(fp_line
			(start 0.120396 0.3048)
			(end 0.120396 0.2794)
			(stroke
				(width 0.1)
				(type default)
			)
			(layer "F.Fab")
		)
		(fp_line
			(start 0.67945 0.3048)
			(end 0.120396 0.3048)
			(stroke
				(width 0.1)
				(type default)
			)
			(layer "F.Fab")
		)
		(fp_line
			(start -0.12065 0.2794)
			(end -0.12065 0.3048)
			(stroke
				(width 0.1)
				(type default)
			)
			(layer "F.Fab")
		)
		(fp_line
			(start 0.120396 0.2794)
			(end -0.12065 0.2794)
			(stroke
				(width 0.1)
				(type default)
			)
			(layer "F.Fab")
		)
		(fp_line
			(start -0.12065 -0.2794)
			(end 0.12065 -0.2794)
			(stroke
				(width 0.1)
				(type default)
			)
			(layer "F.Fab")
		)
		(fp_line
			(start 0.12065 -0.2794)
			(end 0.12065 -0.3048)
			(stroke
				(width 0.1)
				(type default)
			)
			(layer "F.Fab")
		)
		(fp_line
			(start 0.12065 -0.3048)
			(end 0.67945 -0.3048)
			(stroke
				(width 0.1)
				(type default)
			)
			(layer "F.Fab")
		)
		(fp_line
			(start 0.67945 -0.3048)
			(end 0.67945 0.3048)
			(stroke
				(width 0.1)
				(type default)
			)
			(layer "F.Fab")
		)
		(fp_line
			(start -0.67945 -0.305054)
			(end -0.12065 -0.305054)
			(stroke
				(width 0.1)
				(type default)
			)
			(layer "F.Fab")
		)
		(fp_line
			(start -0.12065 -0.305054)
			(end -0.12065 -0.2794)
			(stroke
				(width 0.1)
				(type default)
			)
			(layer "F.Fab")
		)
		(pad "1" smd circle
			(at -0.40005 0 270)
			(size 0 0)
			(layers "F.Cu" "F.Mask" "F.Paste")
			(net "P3V3_AUX")
		)
		(pad "2" smd circle
			(at 0.40005 0 270)
			(size 0 0)
			(layers "F.Cu" "F.Mask" "F.Paste")
			(net "FM_P2E_BUF2_EQA1")
		)
	)
	(footprint ""
		(layer "F.Cu")
		(at 194.856608 -405.102822)
		(property "Reference" "PR3916"
			(at 0 0 0)
			(layer "F.SilkS")
			(hide yes)
			(effects
				(font
					(size 1.27 1.27)
				)
			)
		)
		(property "Value" ""
			(at 0 0 0)
			(layer "F.Fab")
			(effects
				(font
					(size 1.27 1.27)
				)
			)
		)
		(duplicate_pad_numbers_are_jumpers no)
		(fp_line
			(start -0.7874 -0.4064)
			(end 0.7874 -0.4064)
			(stroke
				(width 0.1524)
				(type default)
			)
			(layer "F.SilkS")
		)
		(fp_line
			(start -0.7874 0.4064)
			(end -0.7874 -0.4064)
			(stroke
				(width 0.1524)
				(type default)
			)
			(layer "F.SilkS")
		)
		(fp_line
			(start 0.7874 -0.4064)
			(end 0.7874 0.4064)
			(stroke
				(width 0.1524)
				(type default)
			)
			(layer "F.SilkS")
		)
		(fp_line
			(start 0.7874 0.4064)
			(end -0.7874 0.4064)
			(stroke
				(width 0.1524)
				(type default)
			)
			(layer "F.SilkS")
		)
		(fp_line
			(start -0.67945 -0.305054)
			(end -0.12065 -0.305054)
			(stroke
				(width 0.1)
				(type default)
			)
			(layer "F.Fab")
		)
		(fp_line
			(start -0.67945 0.3048)
			(end -0.67945 -0.305054)
			(stroke
				(width 0.1)
				(type default)
			)
			(layer "F.Fab")
		)
		(fp_line
			(start -0.12065 -0.305054)
			(end -0.12065 -0.2794)
			(stroke
				(width 0.1)
				(type default)
			)
			(layer "F.Fab")
		)
		(fp_line
			(start -0.12065 -0.2794)
			(end 0.12065 -0.2794)
			(stroke
				(width 0.1)
				(type default)
			)
			(layer "F.Fab")
		)
		(fp_line
			(start -0.12065 0.2794)
			(end -0.12065 0.3048)
			(stroke
				(width 0.1)
				(type default)
			)
			(layer "F.Fab")
		)
		(fp_line
			(start -0.12065 0.3048)
			(end -0.67945 0.3048)
			(stroke
				(width 0.1)
				(type default)
			)
			(layer "F.Fab")
		)
		(fp_line
			(start 0.120396 0.2794)
			(end -0.12065 0.2794)
			(stroke
				(width 0.1)
				(type default)
			)
			(layer "F.Fab")
		)
		(fp_line
			(start 0.120396 0.3048)
			(end 0.120396 0.2794)
			(stroke
				(width 0.1)
				(type default)
			)
			(layer "F.Fab")
		)
		(fp_line
			(start 0.12065 -0.3048)
			(end 0.67945 -0.3048)
			(stroke
				(width 0.1)
				(type default)
			)
			(layer "F.Fab")
		)
		(fp_line
			(start 0.12065 -0.2794)
			(end 0.12065 -0.3048)
			(stroke
				(width 0.1)
				(type default)
			)
			(layer "F.Fab")
		)
		(fp_line
			(start 0.67945 -0.3048)
			(end 0.67945 0.3048)
			(stroke
				(width 0.1)
				(type default)
			)
			(layer "F.Fab")
		)
		(fp_line
			(start 0.67945 0.3048)
			(end 0.120396 0.3048)
			(stroke
				(width 0.1)
				(type default)
			)
			(layer "F.Fab")
		)
		(pad "1" smd circle
			(at -0.40005 0)
			(size 0 0)
			(layers "F.Cu" "F.Mask" "F.Paste")
			(net "HSC_SCREF")
		)
		(pad "2" smd circle
			(at 0.40005 0)
			(size 0 0)
			(layers "F.Cu" "F.Mask" "F.Paste")
			(net "HSC_SCREF_1")
		)
	)
)
